(kicad_pcb
	(version 20260206)
	(generator "pcbnew")
	(generator_version "10.0")
	(general
		(thickness 1.6)
		(legacy_teardrops no)
	)
	(paper "A4")
	(title_block
		(title "Wiwynn_Tioga_Pass_MB.brd")
		(comment 1 "Tioga Pass / footprint 2018 of 4770 (J1G1), pads 124-243 of 291")
	)
	(layers
		(0 "F.Cu" signal "TOP")
		(4 "In1.Cu" signal "L2GND")
		(6 "In2.Cu" signal "L3")
		(8 "In3.Cu" signal "L4GND")
		(10 "In4.Cu" signal "L5")
		(12 "In5.Cu" signal "L6GND")
		(14 "In6.Cu" signal "L7VCC")
		(16 "In7.Cu" signal "L8VCC")
		(18 "In8.Cu" signal "L9GND")
		(20 "In9.Cu" signal "L10")
		(22 "In10.Cu" signal "L11GND")
		(24 "In11.Cu" signal "L12")
		(26 "In12.Cu" signal "L13GND")
		(2 "B.Cu" signal "BOTTOM")
		(9 "F.Adhes" user "F.Adhesive")
		(11 "B.Adhes" user "B.Adhesive")
		(13 "F.Paste" user "Package Geometry/Pastemask Top")
		(15 "B.Paste" user "Package Geometry/Pastemask Bottom")
		(5 "F.SilkS" user "Ref Des/Silkscreen Top")
		(7 "B.SilkS" user "Ref Des/Silkscreen Bottom")
		(1 "F.Mask" user "Board Geometry/Soldermask Top")
		(3 "B.Mask" user "Board Geometry/Soldermask Bottom")
		(17 "Dwgs.User" user "User.Drawings")
		(19 "Cmts.User" user "User.Comments")
		(21 "Eco1.User" user "User.Eco1")
		(23 "Eco2.User" user "User.Eco2")
		(25 "Edge.Cuts" user "Board Geometry/Outline")
		(27 "Margin" user)
		(31 "F.CrtYd" user "Package Geometry/Place Bound Top")
		(29 "B.CrtYd" user "Package Geometry/Place Bound Bottom")
		(35 "F.Fab" user "Ref Des/Assembly Top")
		(33 "B.Fab" user "Ref Des/Assembly Bottom")
	)
	(footprint ""
		(layer "F.Cu")
		(at 29.699458 -15.423642 90)
		(property "Reference" "J1G1"
			(at 9.314688 35.070542 0)
			(unlocked yes)
			(layer "F.SilkS")
			(effects
				(font
					(size 0.7874 0.5842)
					(thickness 0.1524)
				)
				(justify left)
			)
		)
		(property "Value" ""
			(at 0 0 90)
			(layer "F.Fab")
			(effects
				(font
					(size 1.27 1.27)
				)
			)
		)
		(duplicate_pad_numbers_are_jumpers no)
		(pad "121" smd rect
			(at 0 107.100116 90)
			(size 1.8034 0.508)
			(layers "F.Cu" "F.Mask" "F.Paste")
			(net "M_G_DQS_DP<15>")
		)
		(pad "122" smd rect
			(at 0 107.95 90)
			(size 1.8034 0.508)
			(layers "F.Cu" "F.Mask" "F.Paste")
			(net "M_G_DQS_DN<15>")
		)
		(pad "123" smd rect
			(at 0 108.799884 90)
			(size 1.8034 0.508)
			(layers "F.Cu" "F.Mask" "F.Paste")
			(net "GND")
		)
		(pad "124" smd rect
			(at 0 109.650022 90)
			(size 1.8034 0.508)
			(layers "F.Cu" "F.Mask" "F.Paste")
			(net "M_G_DQ<55>")
		)
		(pad "125" smd rect
			(at 0 110.499906 90)
			(size 1.8034 0.508)
			(layers "F.Cu" "F.Mask" "F.Paste")
			(net "GND")
		)
		(pad "126" smd rect
			(at 0 111.350044 90)
			(size 1.8034 0.508)
			(layers "F.Cu" "F.Mask" "F.Paste")
			(net "M_G_DQ<51>")
		)
		(pad "127" smd rect
			(at 0 112.199928 90)
			(size 1.8034 0.508)
			(layers "F.Cu" "F.Mask" "F.Paste")
			(net "GND")
		)
		(pad "128" smd rect
			(at 0 113.050066 90)
			(size 1.8034 0.508)
			(layers "F.Cu" "F.Mask" "F.Paste")
			(net "M_G_DQ<61>")
		)
		(pad "129" smd rect
			(at 0 113.89995 90)
			(size 1.8034 0.508)
			(layers "F.Cu" "F.Mask" "F.Paste")
			(net "GND")
		)
		(pad "130" smd rect
			(at 0 114.750088 90)
			(size 1.8034 0.508)
			(layers "F.Cu" "F.Mask" "F.Paste")
			(net "M_G_DQ<57>")
		)
		(pad "131" smd rect
			(at 0 115.599972 90)
			(size 1.8034 0.508)
			(layers "F.Cu" "F.Mask" "F.Paste")
			(net "GND")
		)
		(pad "132" smd rect
			(at 0 116.45011 90)
			(size 1.8034 0.508)
			(layers "F.Cu" "F.Mask" "F.Paste")
			(net "M_G_DQS_DP<16>")
		)
		(pad "133" smd rect
			(at 0 117.299994 90)
			(size 1.8034 0.508)
			(layers "F.Cu" "F.Mask" "F.Paste")
			(net "M_G_DQS_DN<16>")
		)
		(pad "134" smd rect
			(at 0 118.149878 90)
			(size 1.8034 0.508)
			(layers "F.Cu" "F.Mask" "F.Paste")
			(net "GND")
		)
		(pad "135" smd rect
			(at 0 119.000016 90)
			(size 1.8034 0.508)
			(layers "F.Cu" "F.Mask" "F.Paste")
			(net "M_G_DQ<63>")
		)
		(pad "136" smd rect
			(at 0 119.8499 90)
			(size 1.8034 0.508)
			(layers "F.Cu" "F.Mask" "F.Paste")
			(net "GND")
		)
		(pad "137" smd rect
			(at 0 120.700038 90)
			(size 1.8034 0.508)
			(layers "F.Cu" "F.Mask" "F.Paste")
			(net "M_G_DQ<59>")
		)
		(pad "138" smd rect
			(at 0 121.549922 90)
			(size 1.8034 0.508)
			(layers "F.Cu" "F.Mask" "F.Paste")
			(net "GND")
		)
		(pad "139" smd rect
			(at 0 122.40006 90)
			(size 1.8034 0.508)
			(layers "F.Cu" "F.Mask" "F.Paste")
			(net "GND")
		)
		(pad "140" smd rect
			(at 0 123.249944 90)
			(size 1.8034 0.508)
			(layers "F.Cu" "F.Mask" "F.Paste")
			(net "GND")
		)
		(pad "141" smd rect
			(at 0 124.100082 90)
			(size 1.8034 0.508)
			(layers "F.Cu" "F.Mask" "F.Paste")
			(net "SMB_DDR_GHJ_VPP_SCL")
		)
		(pad "142" smd rect
			(at 0 124.949966 90)
			(size 1.8034 0.508)
			(layers "F.Cu" "F.Mask" "F.Paste")
			(net "PVPP_GHJ")
		)
		(pad "143" smd rect
			(at 0 125.800104 90)
			(size 1.8034 0.508)
			(layers "F.Cu" "F.Mask" "F.Paste")
			(net "PVPP_GHJ")
		)
		(pad "144" smd rect
			(at 0 126.649988 90)
			(size 1.8034 0.508)
			(layers "F.Cu" "F.Mask" "F.Paste")
			(net "TP_CH_G_DIMM_G0_RFU_2")
		)
		(pad "145" smd rect
			(at 4.59994 0 90)
			(size 1.8034 0.508)
			(layers "F.Cu" "F.Mask" "F.Paste")
			(net "P12V_NVDIMM_GHJ")
		)
		(pad "146" smd rect
			(at 4.59994 0.849884 90)
			(size 1.8034 0.508)
			(layers "F.Cu" "F.Mask" "F.Paste")
			(net "M_G_VREF")
		)
		(pad "147" smd rect
			(at 4.59994 1.700022 90)
			(size 1.8034 0.508)
			(layers "F.Cu" "F.Mask" "F.Paste")
			(net "GND")
		)
		(pad "148" smd rect
			(at 4.59994 2.549906 90)
			(size 1.8034 0.508)
			(layers "F.Cu" "F.Mask" "F.Paste")
			(net "M_G_DQ<4>")
		)
		(pad "149" smd rect
			(at 4.59994 3.400044 90)
			(size 1.8034 0.508)
			(layers "F.Cu" "F.Mask" "F.Paste")
			(net "GND")
		)
		(pad "150" smd rect
			(at 4.59994 4.249928 90)
			(size 1.8034 0.508)
			(layers "F.Cu" "F.Mask" "F.Paste")
			(net "M_G_DQ<0>")
		)
		(pad "151" smd rect
			(at 4.59994 5.100066 90)
			(size 1.8034 0.508)
			(layers "F.Cu" "F.Mask" "F.Paste")
			(net "GND")
		)
		(pad "152" smd rect
			(at 4.59994 5.94995 90)
			(size 1.8034 0.508)
			(layers "F.Cu" "F.Mask" "F.Paste")
			(net "M_G_DQS_DN<0>")
		)
		(pad "153" smd rect
			(at 4.59994 6.800088 90)
			(size 1.8034 0.508)
			(layers "F.Cu" "F.Mask" "F.Paste")
			(net "M_G_DQS_DP<0>")
		)
		(pad "154" smd rect
			(at 4.59994 7.649972 90)
			(size 1.8034 0.508)
			(layers "F.Cu" "F.Mask" "F.Paste")
			(net "GND")
		)
		(pad "155" smd rect
			(at 4.59994 8.50011 90)
			(size 1.8034 0.508)
			(layers "F.Cu" "F.Mask" "F.Paste")
			(net "M_G_DQ<6>")
		)
		(pad "156" smd rect
			(at 4.59994 9.349994 90)
			(size 1.8034 0.508)
			(layers "F.Cu" "F.Mask" "F.Paste")
			(net "GND")
		)
		(pad "157" smd rect
			(at 4.59994 10.199878 90)
			(size 1.8034 0.508)
			(layers "F.Cu" "F.Mask" "F.Paste")
			(net "M_G_DQ<2>")
		)
		(pad "158" smd rect
			(at 4.59994 11.050016 90)
			(size 1.8034 0.508)
			(layers "F.Cu" "F.Mask" "F.Paste")
			(net "GND")
		)
		(pad "159" smd rect
			(at 4.59994 11.8999 90)
			(size 1.8034 0.508)
			(layers "F.Cu" "F.Mask" "F.Paste")
			(net "M_G_DQ<12>")
		)
		(pad "160" smd rect
			(at 4.59994 12.750038 90)
			(size 1.8034 0.508)
			(layers "F.Cu" "F.Mask" "F.Paste")
			(net "GND")
		)
		(pad "161" smd rect
			(at 4.59994 13.599922 90)
			(size 1.8034 0.508)
			(layers "F.Cu" "F.Mask" "F.Paste")
			(net "M_G_DQ<8>")
		)
		(pad "162" smd rect
			(at 4.59994 14.45006 90)
			(size 1.8034 0.508)
			(layers "F.Cu" "F.Mask" "F.Paste")
			(net "GND")
		)
		(pad "163" smd rect
			(at 4.59994 15.299944 90)
			(size 1.8034 0.508)
			(layers "F.Cu" "F.Mask" "F.Paste")
			(net "M_G_DQS_DN<1>")
		)
		(pad "164" smd rect
			(at 4.59994 16.150082 90)
			(size 1.8034 0.508)
			(layers "F.Cu" "F.Mask" "F.Paste")
			(net "M_G_DQS_DP<1>")
		)
		(pad "165" smd rect
			(at 4.59994 16.999966 90)
			(size 1.8034 0.508)
			(layers "F.Cu" "F.Mask" "F.Paste")
			(net "GND")
		)
		(pad "166" smd rect
			(at 4.59994 17.850104 90)
			(size 1.8034 0.508)
			(layers "F.Cu" "F.Mask" "F.Paste")
			(net "M_G_DQ<14>")
		)
		(pad "167" smd rect
			(at 4.59994 18.699988 90)
			(size 1.8034 0.508)
			(layers "F.Cu" "F.Mask" "F.Paste")
			(net "GND")
		)
		(pad "168" smd rect
			(at 4.59994 19.550126 90)
			(size 1.8034 0.508)
			(layers "F.Cu" "F.Mask" "F.Paste")
			(net "M_G_DQ<10>")
		)
		(pad "169" smd rect
			(at 4.59994 20.40001 90)
			(size 1.8034 0.508)
			(layers "F.Cu" "F.Mask" "F.Paste")
			(net "GND")
		)
		(pad "170" smd rect
			(at 4.59994 21.249894 90)
			(size 1.8034 0.508)
			(layers "F.Cu" "F.Mask" "F.Paste")
			(net "M_G_DQ<20>")
		)
		(pad "171" smd rect
			(at 4.59994 22.100032 90)
			(size 1.8034 0.508)
			(layers "F.Cu" "F.Mask" "F.Paste")
			(net "GND")
		)
		(pad "172" smd rect
			(at 4.59994 22.949916 90)
			(size 1.8034 0.508)
			(layers "F.Cu" "F.Mask" "F.Paste")
			(net "M_G_DQ<16>")
		)
		(pad "173" smd rect
			(at 4.59994 23.800054 90)
			(size 1.8034 0.508)
			(layers "F.Cu" "F.Mask" "F.Paste")
			(net "GND")
		)
		(pad "174" smd rect
			(at 4.59994 24.649938 90)
			(size 1.8034 0.508)
			(layers "F.Cu" "F.Mask" "F.Paste")
			(net "M_G_DQS_DN<2>")
		)
		(pad "175" smd rect
			(at 4.59994 25.500076 90)
			(size 1.8034 0.508)
			(layers "F.Cu" "F.Mask" "F.Paste")
			(net "M_G_DQS_DP<2>")
		)
		(pad "176" smd rect
			(at 4.59994 26.34996 90)
			(size 1.8034 0.508)
			(layers "F.Cu" "F.Mask" "F.Paste")
			(net "GND")
		)
		(pad "177" smd rect
			(at 4.59994 27.200098 90)
			(size 1.8034 0.508)
			(layers "F.Cu" "F.Mask" "F.Paste")
			(net "M_G_DQ<22>")
		)
		(pad "178" smd rect
			(at 4.59994 28.049982 90)
			(size 1.8034 0.508)
			(layers "F.Cu" "F.Mask" "F.Paste")
			(net "GND")
		)
		(pad "179" smd rect
			(at 4.59994 28.90012 90)
			(size 1.8034 0.508)
			(layers "F.Cu" "F.Mask" "F.Paste")
			(net "M_G_DQ<18>")
		)
		(pad "180" smd rect
			(at 4.59994 29.750004 90)
			(size 1.8034 0.508)
			(layers "F.Cu" "F.Mask" "F.Paste")
			(net "GND")
		)
		(pad "181" smd rect
			(at 4.59994 30.599888 90)
			(size 1.8034 0.508)
			(layers "F.Cu" "F.Mask" "F.Paste")
			(net "M_G_DQ<28>")
		)
		(pad "182" smd rect
			(at 4.59994 31.450026 90)
			(size 1.8034 0.508)
			(layers "F.Cu" "F.Mask" "F.Paste")
			(net "GND")
		)
		(pad "183" smd rect
			(at 4.59994 32.29991 90)
			(size 1.8034 0.508)
			(layers "F.Cu" "F.Mask" "F.Paste")
			(net "M_G_DQ<24>")
		)
		(pad "184" smd rect
			(at 4.59994 33.150048 90)
			(size 1.8034 0.508)
			(layers "F.Cu" "F.Mask" "F.Paste")
			(net "GND")
		)
		(pad "185" smd rect
			(at 4.59994 33.999932 90)
			(size 1.8034 0.508)
			(layers "F.Cu" "F.Mask" "F.Paste")
			(net "M_G_DQS_DN<3>")
		)
		(pad "186" smd rect
			(at 4.59994 34.85007 90)
			(size 1.8034 0.508)
			(layers "F.Cu" "F.Mask" "F.Paste")
			(net "M_G_DQS_DP<3>")
		)
		(pad "187" smd rect
			(at 4.59994 35.699954 90)
			(size 1.8034 0.508)
			(layers "F.Cu" "F.Mask" "F.Paste")
			(net "GND")
		)
		(pad "188" smd rect
			(at 4.59994 36.550092 90)
			(size 1.8034 0.508)
			(layers "F.Cu" "F.Mask" "F.Paste")
			(net "M_G_DQ<30>")
		)
		(pad "189" smd rect
			(at 4.59994 37.399976 90)
			(size 1.8034 0.508)
			(layers "F.Cu" "F.Mask" "F.Paste")
			(net "GND")
		)
		(pad "190" smd rect
			(at 4.59994 38.250114 90)
			(size 1.8034 0.508)
			(layers "F.Cu" "F.Mask" "F.Paste")
			(net "M_G_DQ<26>")
		)
		(pad "191" smd rect
			(at 4.59994 39.099998 90)
			(size 1.8034 0.508)
			(layers "F.Cu" "F.Mask" "F.Paste")
			(net "GND")
		)
		(pad "192" smd rect
			(at 4.59994 39.949882 90)
			(size 1.8034 0.508)
			(layers "F.Cu" "F.Mask" "F.Paste")
			(net "M_G_ECC<4>")
		)
		(pad "193" smd rect
			(at 4.59994 40.80002 90)
			(size 1.8034 0.508)
			(layers "F.Cu" "F.Mask" "F.Paste")
			(net "GND")
		)
		(pad "194" smd rect
			(at 4.59994 41.649904 90)
			(size 1.8034 0.508)
			(layers "F.Cu" "F.Mask" "F.Paste")
			(net "M_G_ECC<0>")
		)
		(pad "195" smd rect
			(at 4.59994 42.500042 90)
			(size 1.8034 0.508)
			(layers "F.Cu" "F.Mask" "F.Paste")
			(net "GND")
		)
		(pad "196" smd rect
			(at 4.59994 43.349926 90)
			(size 1.8034 0.508)
			(layers "F.Cu" "F.Mask" "F.Paste")
			(net "M_G_DQS_DN<8>")
		)
		(pad "197" smd rect
			(at 4.59994 44.200064 90)
			(size 1.8034 0.508)
			(layers "F.Cu" "F.Mask" "F.Paste")
			(net "M_G_DQS_DP<8>")
		)
		(pad "198" smd rect
			(at 4.59994 45.049948 90)
			(size 1.8034 0.508)
			(layers "F.Cu" "F.Mask" "F.Paste")
			(net "GND")
		)
		(pad "199" smd rect
			(at 4.59994 45.900086 90)
			(size 1.8034 0.508)
			(layers "F.Cu" "F.Mask" "F.Paste")
			(net "M_G_ECC<6>")
		)
		(pad "200" smd rect
			(at 4.59994 46.74997 90)
			(size 1.8034 0.508)
			(layers "F.Cu" "F.Mask" "F.Paste")
			(net "GND")
		)
		(pad "201" smd rect
			(at 4.59994 47.600108 90)
			(size 1.8034 0.508)
			(layers "F.Cu" "F.Mask" "F.Paste")
			(net "M_G_ECC<2>")
		)
		(pad "202" smd rect
			(at 4.59994 48.449992 90)
			(size 1.8034 0.508)
			(layers "F.Cu" "F.Mask" "F.Paste")
			(net "GND")
		)
		(pad "203" smd rect
			(at 4.59994 49.299876 90)
			(size 1.8034 0.508)
			(layers "F.Cu" "F.Mask" "F.Paste")
			(net "M_G_CKE<1>")
		)
		(pad "204" smd rect
			(at 4.59994 50.150014 90)
			(size 1.8034 0.508)
			(layers "F.Cu" "F.Mask" "F.Paste")
			(net "PVDDQ_GHJ")
		)
		(pad "205" smd rect
			(at 4.59994 50.999898 90)
			(size 1.8034 0.508)
			(layers "F.Cu" "F.Mask" "F.Paste")
			(net "TP_CH_G_DIMM_G0_RFU_0")
		)
		(pad "206" smd rect
			(at 4.59994 51.850036 90)
			(size 1.8034 0.508)
			(layers "F.Cu" "F.Mask" "F.Paste")
			(net "PVDDQ_GHJ")
		)
		(pad "207" smd rect
			(at 4.59994 52.69992 90)
			(size 1.8034 0.508)
			(layers "F.Cu" "F.Mask" "F.Paste")
			(net "M_G_BG<1>")
		)
		(pad "208" smd rect
			(at 4.59994 53.550058 90)
			(size 1.8034 0.508)
			(layers "F.Cu" "F.Mask" "F.Paste")
			(net "M_G_ALERT_N")
		)
		(pad "209" smd rect
			(at 4.59994 54.399942 90)
			(size 1.8034 0.508)
			(layers "F.Cu" "F.Mask" "F.Paste")
			(net "PVDDQ_GHJ")
		)
		(pad "210" smd rect
			(at 4.59994 55.25008 90)
			(size 1.8034 0.508)
			(layers "F.Cu" "F.Mask" "F.Paste")
			(net "M_G_MA<11>")
		)
		(pad "211" smd rect
			(at 4.59994 56.099964 90)
			(size 1.8034 0.508)
			(layers "F.Cu" "F.Mask" "F.Paste")
			(net "M_G_MA<7>")
		)
		(pad "212" smd rect
			(at 4.59994 56.950102 90)
			(size 1.8034 0.508)
			(layers "F.Cu" "F.Mask" "F.Paste")
			(net "PVDDQ_GHJ")
		)
		(pad "213" smd rect
			(at 4.59994 57.799986 90)
			(size 1.8034 0.508)
			(layers "F.Cu" "F.Mask" "F.Paste")
			(net "M_G_MA<5>")
		)
		(pad "214" smd rect
			(at 4.59994 58.650124 90)
			(size 1.8034 0.508)
			(layers "F.Cu" "F.Mask" "F.Paste")
			(net "M_G_MA<4>")
		)
		(pad "215" smd rect
			(at 4.59994 59.500008 90)
			(size 1.8034 0.508)
			(layers "F.Cu" "F.Mask" "F.Paste")
			(net "PVDDQ_GHJ")
		)
		(pad "216" smd rect
			(at 4.59994 60.349892 90)
			(size 1.8034 0.508)
			(layers "F.Cu" "F.Mask" "F.Paste")
			(net "M_G_MA<2>")
		)
		(pad "217" smd rect
			(at 4.59994 61.20003 90)
			(size 1.8034 0.508)
			(layers "F.Cu" "F.Mask" "F.Paste")
			(net "PVDDQ_GHJ")
		)
		(pad "218" smd rect
			(at 4.59994 62.049914 90)
			(size 1.8034 0.508)
			(layers "F.Cu" "F.Mask" "F.Paste")
			(net "M_G_CLK_DP<1>")
		)
		(pad "219" smd rect
			(at 4.59994 62.900052 90)
			(size 1.8034 0.508)
			(layers "F.Cu" "F.Mask" "F.Paste")
			(net "M_G_CLK_DN<1>")
		)
		(pad "220" smd rect
			(at 4.59994 63.749936 90)
			(size 1.8034 0.508)
			(layers "F.Cu" "F.Mask" "F.Paste")
			(net "PVDDQ_GHJ")
		)
		(pad "221" smd rect
			(at 4.59994 64.600074 90)
			(size 1.8034 0.508)
			(layers "F.Cu" "F.Mask" "F.Paste")
			(net "PVTT_GHJ")
		)
		(pad "222" smd rect
			(at 4.59994 70.550024 90)
			(size 1.8034 0.508)
			(layers "F.Cu" "F.Mask" "F.Paste")
			(net "M_G_PAR")
		)
		(pad "223" smd rect
			(at 4.59994 71.399908 90)
			(size 1.8034 0.508)
			(layers "F.Cu" "F.Mask" "F.Paste")
			(net "PVDDQ_GHJ")
		)
		(pad "224" smd rect
			(at 4.59994 72.250046 90)
			(size 1.8034 0.508)
			(layers "F.Cu" "F.Mask" "F.Paste")
			(net "M_G_BA<1>")
		)
		(pad "225" smd rect
			(at 4.59994 73.09993 90)
			(size 1.8034 0.508)
			(layers "F.Cu" "F.Mask" "F.Paste")
			(net "M_G_MA<10>")
		)
		(pad "226" smd rect
			(at 4.59994 73.950068 90)
			(size 1.8034 0.508)
			(layers "F.Cu" "F.Mask" "F.Paste")
			(net "PVDDQ_GHJ")
		)
		(pad "227" smd rect
			(at 4.59994 74.799952 90)
			(size 1.8034 0.508)
			(layers "F.Cu" "F.Mask" "F.Paste")
			(net "TP_CH_G_DIMM_G0_RFU_1")
		)
		(pad "228" smd rect
			(at 4.59994 75.65009 90)
			(size 1.8034 0.508)
			(layers "F.Cu" "F.Mask" "F.Paste")
			(net "M_G_MA<14>")
		)
		(pad "229" smd rect
			(at 4.59994 76.499974 90)
			(size 1.8034 0.508)
			(layers "F.Cu" "F.Mask" "F.Paste")
			(net "PVDDQ_GHJ")
		)
		(pad "230" smd rect
			(at 4.59994 77.350112 90)
			(size 1.8034 0.508)
			(layers "F.Cu" "F.Mask" "F.Paste")
			(net "FM_ADR_COMPLETE_GHJ_N")
		)
		(pad "231" smd rect
			(at 4.59994 78.199996 90)
			(size 1.8034 0.508)
			(layers "F.Cu" "F.Mask" "F.Paste")
			(net "PVDDQ_GHJ")
		)
		(pad "232" smd rect
			(at 4.59994 79.04988 90)
			(size 1.8034 0.508)
			(layers "F.Cu" "F.Mask" "F.Paste")
			(net "M_G_MA<13>")
		)
		(pad "233" smd rect
			(at 4.59994 79.900018 90)
			(size 1.8034 0.508)
			(layers "F.Cu" "F.Mask" "F.Paste")
			(net "PVDDQ_GHJ")
		)
		(pad "234" smd rect
			(at 4.59994 80.749902 90)
			(size 1.8034 0.508)
			(layers "F.Cu" "F.Mask" "F.Paste")
			(net "M_G_MA<17>")
		)
		(pad "235" smd rect
			(at 4.59994 81.60004 90)
			(size 1.8034 0.508)
			(layers "F.Cu" "F.Mask" "F.Paste")
			(net "M_G_C<2>")
		)
		(pad "236" smd rect
			(at 4.59994 82.449924 90)
			(size 1.8034 0.508)
			(layers "F.Cu" "F.Mask" "F.Paste")
			(net "PVDDQ_GHJ")
		)
		(pad "237" smd rect
			(at 4.59994 83.300062 90)
			(size 1.8034 0.508)
			(layers "F.Cu" "F.Mask" "F.Paste")
			(net "M_G_CS_N<3>")
		)
		(pad "238" smd rect
			(at 4.59994 84.149946 90)
			(size 1.8034 0.508)
			(layers "F.Cu" "F.Mask" "F.Paste")
			(net "GND")
		)
		(pad "239" smd rect
			(at 4.59994 85.000084 90)
			(size 1.8034 0.508)
			(layers "F.Cu" "F.Mask" "F.Paste")
			(net "GND")
		)
		(pad "240" smd rect
			(at 4.59994 85.849968 90)
			(size 1.8034 0.508)
			(layers "F.Cu" "F.Mask" "F.Paste")
			(net "M_G_DQ<36>")
		)
	)
)
